(kicad_pcb
	(version 20260206)
	(generator "pcbnew")
	(generator_version "10.0")
	(general
		(thickness 1.6)
		(legacy_teardrops no)
	)
	(paper "A4")
	(title_block
		(title "panther-plus-userver — 13130-1b_20150205.brd")
		(comment 1 "Honey Badger (Wiwynn) / footprints 958-965 of 1509")
	)
	(layers
		(0 "F.Cu" signal "TOP")
		(4 "In1.Cu" signal "L2")
		(6 "In2.Cu" signal "L3")
		(8 "In3.Cu" signal "L4")
		(10 "In4.Cu" signal "L5")
		(12 "In5.Cu" signal "L6")
		(14 "In6.Cu" signal "L7")
		(16 "In7.Cu" signal "L8")
		(18 "In8.Cu" signal "L9")
		(20 "In9.Cu" signal "L10")
		(22 "In10.Cu" signal "L11")
		(2 "B.Cu" signal "BOTTOM")
		(9 "F.Adhes" user "F.Adhesive")
		(11 "B.Adhes" user "B.Adhesive")
		(13 "F.Paste" user "Package Geometry/Pastemask Top")
		(15 "B.Paste" user "Package Geometry/Pastemask Bottom")
		(5 "F.SilkS" user "Ref Des/Silkscreen Top")
		(7 "B.SilkS" user "Ref Des/Silkscreen Bottom")
		(1 "F.Mask" user "Board Geometry/Soldermask Top")
		(3 "B.Mask" user "Board Geometry/Soldermask Bottom")
		(17 "Dwgs.User" user "User.Drawings")
		(19 "Cmts.User" user "User.Comments")
		(21 "Eco1.User" user "User.Eco1")
		(23 "Eco2.User" user "User.Eco2")
		(25 "Edge.Cuts" user "Board Geometry/Outline")
		(27 "Margin" user)
		(31 "F.CrtYd" user "Package Geometry/Place Bound Top")
		(29 "B.CrtYd" user "Package Geometry/Place Bound Bottom")
		(35 "F.Fab" user "Ref Des/Assembly Top")
		(33 "B.Fab" user "Ref Des/Assembly Bottom")
	)
	(footprint ""
		(layer "B.Cu")
		(at 100.457 -19.431)
		(property "Reference" "C256"
			(at 0 0 0)
			(layer "B.SilkS")
			(hide yes)
			(effects
				(font
					(size 1.27 1.27)
				)
				(justify mirror)
			)
		)
		(property "Value" "SC1U10V2KX-1GP"
			(at -1.1811 -2.7051 0)
			(unlocked yes)
			(layer "B.Fab")
			(hide yes)
			(effects
				(font
					(size 1.016 1.016)
					(thickness 0.1524)
				)
				(justify mirror)
			)
		)
		(property "Device Type" "C402H22"
			(at -1.1811 -4.2291 0)
			(unlocked yes)
			(layer "B.Fab")
			(hide yes)
			(effects
				(font
					(size 1.016 1.016)
					(thickness 0.1524)
				)
				(justify mirror)
			)
		)
		(duplicate_pad_numbers_are_jumpers no)
		(fp_rect
			(start 0.381 0.7366)
			(end -0.381 -0.7366)
			(stroke
				(width 0)
				(type default)
			)
			(fill no)
			(layer "B.CrtYd")
		)
		(fp_rect
			(start 0.381 0.7366)
			(end -0.381 -0.7366)
			(stroke
				(width 0)
				(type default)
			)
			(fill no)
			(layer "B.Fab")
		)
		(pad "1" smd custom
			(at 0 -0.4572 180)
			(size 0.1143 0.1143)
			(layers "B.Cu" "B.Mask" "B.Paste")
			(net "VCCCLKDDR1")
			(options
				(clearance outline)
				(anchor circle)
			)
			(primitives
				(gr_poly
					(pts
						(arc
							(start -0.254 0.1778)
							(mid -0.239121 0.213721)
							(end -0.2032 0.2286)
						)
						(arc
							(start 0.2032 0.2286)
							(mid 0.239121 0.213721)
							(end 0.254 0.1778)
						)
						(arc
							(start 0.254 -0.1778)
							(mid 0.239121 -0.213721)
							(end 0.2032 -0.2286)
						)
						(arc
							(start -0.2032 -0.2286)
							(mid -0.239121 -0.213721)
							(end -0.254 -0.1778)
						)
					)
					(width 0)
					(fill yes)
				)
			)
		)
		(pad "2" smd custom
			(at 0 0.4572 180)
			(size 0.1143 0.1143)
			(layers "B.Cu" "B.Mask" "B.Paste")
			(net "GND")
			(options
				(clearance outline)
				(anchor circle)
			)
			(primitives
				(gr_poly
					(pts
						(arc
							(start -0.254 0.1778)
							(mid -0.239121 0.213721)
							(end -0.2032 0.2286)
						)
						(arc
							(start 0.2032 0.2286)
							(mid 0.239121 0.213721)
							(end 0.254 0.1778)
						)
						(arc
							(start 0.254 -0.1778)
							(mid 0.239121 -0.213721)
							(end 0.2032 -0.2286)
						)
						(arc
							(start -0.2032 -0.2286)
							(mid -0.239121 -0.213721)
							(end -0.254 -0.1778)
						)
					)
					(width 0)
					(fill yes)
				)
			)
		)
	)
	(footprint ""
		(layer "B.Cu")
		(at 35.814 -51.054 -90)
		(property "Reference" "R252"
			(at 0 0 90)
			(layer "B.SilkS")
			(hide yes)
			(effects
				(font
					(size 1.27 1.27)
				)
				(justify mirror)
			)
		)
		(property "Value" "4K75R2F-1-GP"
			(at -1.7907 -1.1176 270)
			(unlocked yes)
			(layer "B.Fab")
			(hide yes)
			(effects
				(font
					(size 1.016 1.016)
					(thickness 0.1524)
				)
				(justify mirror)
			)
		)
		(property "Device Type" "R402H16"
			(at -1.7907 -2.6416 270)
			(unlocked yes)
			(layer "B.Fab")
			(hide yes)
			(effects
				(font
					(size 1.016 1.016)
					(thickness 0.1524)
				)
				(justify mirror)
			)
		)
		(duplicate_pad_numbers_are_jumpers no)
		(fp_rect
			(start 0.381 0.8382)
			(end -0.381 -0.8382)
			(stroke
				(width 0)
				(type default)
			)
			(fill no)
			(layer "B.CrtYd")
		)
		(fp_rect
			(start 0.381 0.8382)
			(end -0.381 -0.8382)
			(stroke
				(width 0)
				(type default)
			)
			(fill no)
			(layer "B.Fab")
		)
		(pad "1" smd custom
			(at 0 -0.4318 90)
			(size 0.127 0.127)
			(layers "B.Cu" "B.Mask" "B.Paste")
			(net "P3V3_STBY")
			(options
				(clearance outline)
				(anchor circle)
			)
			(primitives
				(gr_poly
					(pts
						(arc
							(start -0.2032 0.2794)
							(mid -0.239121 0.264521)
							(end -0.254 0.2286)
						)
						(arc
							(start -0.254 -0.2286)
							(mid -0.239121 -0.264521)
							(end -0.2032 -0.2794)
						)
						(arc
							(start 0.2032 -0.2794)
							(mid 0.239121 -0.264521)
							(end 0.254 -0.2286)
						)
						(arc
							(start 0.254 0.2286)
							(mid 0.239121 0.264521)
							(end 0.2032 0.2794)
						)
					)
					(width 0)
					(fill yes)
				)
			)
		)
		(pad "2" smd custom
			(at 0 0.4318 90)
			(size 0.127 0.127)
			(layers "B.Cu" "B.Mask" "B.Paste")
			(net "P1V5_STBY_EN")
			(options
				(clearance outline)
				(anchor circle)
			)
			(primitives
				(gr_poly
					(pts
						(arc
							(start -0.2032 0.2794)
							(mid -0.239121 0.264521)
							(end -0.254 0.2286)
						)
						(arc
							(start -0.254 -0.2286)
							(mid -0.239121 -0.264521)
							(end -0.2032 -0.2794)
						)
						(arc
							(start 0.2032 -0.2794)
							(mid 0.239121 -0.264521)
							(end 0.254 -0.2286)
						)
						(arc
							(start 0.254 0.2286)
							(mid 0.239121 0.264521)
							(end 0.2032 0.2794)
						)
					)
					(width 0)
					(fill yes)
				)
			)
		)
	)
	(footprint ""
		(layer "B.Cu")
		(at 73.7108 -38.7858)
		(property "Reference" "R93"
			(at 0 0 0)
			(layer "B.SilkS")
			(hide yes)
			(effects
				(font
					(size 1.27 1.27)
				)
				(justify mirror)
			)
		)
		(property "Value" "1KR2F-3-GP"
			(at -0.064008 -3.993896 0)
			(unlocked yes)
			(layer "B.Fab")
			(hide yes)
			(effects
				(font
					(size 1.016 1.016)
					(thickness 0.1524)
				)
				(justify mirror)
			)
		)
		(property "Device Type" "R402H16"
			(at -0.064008 -5.517896 0)
			(unlocked yes)
			(layer "B.Fab")
			(hide yes)
			(effects
				(font
					(size 1.016 1.016)
					(thickness 0.1524)
				)
				(justify mirror)
			)
		)
		(duplicate_pad_numbers_are_jumpers no)
		(fp_rect
			(start 0.381 0.8382)
			(end -0.381 -0.8382)
			(stroke
				(width 0)
				(type default)
			)
			(fill no)
			(layer "B.CrtYd")
		)
		(fp_rect
			(start 0.381 0.8382)
			(end -0.381 -0.8382)
			(stroke
				(width 0)
				(type default)
			)
			(fill no)
			(layer "B.Fab")
		)
		(pad "1" smd custom
			(at 0 -0.4318 180)
			(size 0.127 0.127)
			(layers "B.Cu" "B.Mask" "B.Paste")
			(net "GND")
			(options
				(clearance outline)
				(anchor circle)
			)
			(primitives
				(gr_poly
					(pts
						(arc
							(start -0.2032 0.2794)
							(mid -0.239121 0.264521)
							(end -0.254 0.2286)
						)
						(arc
							(start -0.254 -0.2286)
							(mid -0.239121 -0.264521)
							(end -0.2032 -0.2794)
						)
						(arc
							(start 0.2032 -0.2794)
							(mid 0.239121 -0.264521)
							(end 0.254 -0.2286)
						)
						(arc
							(start 0.254 0.2286)
							(mid 0.239121 0.264521)
							(end 0.2032 0.2794)
						)
					)
					(width 0)
					(fill yes)
				)
			)
		)
		(pad "2" smd custom
			(at 0 0.4318 180)
			(size 0.127 0.127)
			(layers "B.Cu" "B.Mask" "B.Paste")
			(net "FLEX_CLK_SE0")
			(options
				(clearance outline)
				(anchor circle)
			)
			(primitives
				(gr_poly
					(pts
						(arc
							(start -0.2032 0.2794)
							(mid -0.239121 0.264521)
							(end -0.254 0.2286)
						)
						(arc
							(start -0.254 -0.2286)
							(mid -0.239121 -0.264521)
							(end -0.2032 -0.2794)
						)
						(arc
							(start 0.2032 -0.2794)
							(mid 0.239121 -0.264521)
							(end 0.254 -0.2286)
						)
						(arc
							(start 0.254 0.2286)
							(mid 0.239121 0.264521)
							(end 0.2032 0.2794)
						)
					)
					(width 0)
					(fill yes)
				)
			)
		)
	)
	(footprint ""
		(layer "B.Cu")
		(at 201.2696 -35.5346 90)
		(property "Reference" "LED8"
			(at 0 0 90)
			(layer "B.SilkS")
			(hide yes)
			(effects
				(font
					(size 1.27 1.27)
				)
				(justify mirror)
			)
		)
		(property "Value" "LED-YG-51-GP"
			(at 0.0381 -2.6162 90)
			(unlocked yes)
			(layer "B.Fab")
			(hide yes)
			(effects
				(font
					(size 1.016 1.016)
					(thickness 0.1524)
				)
				(justify mirror)
			)
		)
		(property "Device Type" "LED1608AKH40"
			(at 0.0381 -4.1402 90)
			(unlocked yes)
			(layer "B.Fab")
			(hide yes)
			(effects
				(font
					(size 1.016 1.016)
					(thickness 0.1524)
				)
				(justify mirror)
			)
		)
		(duplicate_pad_numbers_are_jumpers no)
		(fp_line
			(start 0.5334 1.3081)
			(end -0.5334 1.3081)
			(stroke
				(width 0.254)
				(type default)
			)
			(layer "B.SilkS")
		)
		(fp_rect
			(start 0.6604 1.1811)
			(end -0.6604 -1.1811)
			(stroke
				(width 0)
				(type default)
			)
			(fill no)
			(layer "B.CrtYd")
		)
		(fp_rect
			(start 0.6604 1.1811)
			(end -0.6604 -1.1811)
			(stroke
				(width 0)
				(type default)
			)
			(fill no)
			(layer "B.Fab")
		)
		(pad "A" smd rect
			(at 0 -0.652526 270)
			(size 1.0668 0.8128)
			(layers "B.Cu" "B.Mask" "B.Paste")
			(net "PORT80_R_BIT3")
		)
		(pad "K" smd rect
			(at 0 0.652526 270)
			(size 1.0668 0.8128)
			(layers "B.Cu" "B.Mask" "B.Paste")
			(net "PORT80_BIT3")
		)
	)
	(footprint ""
		(layer "B.Cu")
		(at 203.708 -66.675 90)
		(property "Reference" "PC167"
			(at 0 0 90)
			(layer "B.SilkS")
			(hide yes)
			(effects
				(font
					(size 1.27 1.27)
				)
				(justify mirror)
			)
		)
		(property "Value" "SC10U6D3V3MX-GP"
			(at 0.0254 -2.0193 90)
			(unlocked yes)
			(layer "B.Fab")
			(hide yes)
			(effects
				(font
					(size 1.016 1.016)
					(thickness 0.1524)
				)
				(justify mirror)
			)
		)
		(property "Device Type" "C603H38"
			(at 0.0254 -3.5433 90)
			(unlocked yes)
			(layer "B.Fab")
			(hide yes)
			(effects
				(font
					(size 1.016 1.016)
					(thickness 0.1524)
				)
				(justify mirror)
			)
		)
		(duplicate_pad_numbers_are_jumpers no)
		(fp_line
			(start 0.4064 0)
			(end -0.4064 0)
			(stroke
				(width 0.2286)
				(type default)
			)
			(layer "B.SilkS")
		)
		(fp_rect
			(start 0.635 1.1811)
			(end -0.635 -1.1811)
			(stroke
				(width 0)
				(type default)
			)
			(fill no)
			(layer "B.CrtYd")
		)
		(fp_rect
			(start 0.635 1.1811)
			(end -0.635 -1.1811)
			(stroke
				(width 0)
				(type default)
			)
			(fill no)
			(layer "B.Fab")
		)
		(pad "1" smd custom
			(at 0 -0.6604 270)
			(size 0.19685 0.19685)
			(layers "B.Cu" "B.Mask" "B.Paste")
			(net "PV_VDDR")
			(options
				(clearance outline)
				(anchor circle)
			)
			(primitives
				(gr_poly
					(pts
						(arc
							(start 0.508 0.2921)
							(mid 0.478242 0.363942)
							(end 0.4064 0.3937)
						)
						(arc
							(start -0.4064 0.3937)
							(mid -0.478242 0.363942)
							(end -0.508 0.2921)
						)
						(arc
							(start -0.508 -0.2921)
							(mid -0.478242 -0.363942)
							(end -0.4064 -0.3937)
						)
						(arc
							(start 0.4064 -0.3937)
							(mid 0.478242 -0.363942)
							(end 0.508 -0.2921)
						)
					)
					(width 0)
					(fill yes)
				)
			)
		)
		(pad "2" smd custom
			(at 0 0.6604 270)
			(size 0.19685 0.19685)
			(layers "B.Cu" "B.Mask" "B.Paste")
			(net "GND")
			(options
				(clearance outline)
				(anchor circle)
			)
			(primitives
				(gr_poly
					(pts
						(arc
							(start 0.508 0.2921)
							(mid 0.478242 0.363942)
							(end 0.4064 0.3937)
						)
						(arc
							(start -0.4064 0.3937)
							(mid -0.478242 0.363942)
							(end -0.508 0.2921)
						)
						(arc
							(start -0.508 -0.2921)
							(mid -0.478242 -0.363942)
							(end -0.4064 -0.3937)
						)
						(arc
							(start 0.4064 -0.3937)
							(mid 0.478242 -0.363942)
							(end 0.508 -0.2921)
						)
					)
					(width 0)
					(fill yes)
				)
			)
		)
	)
	(footprint ""
		(layer "B.Cu")
		(at 81.915 -65.786)
		(property "Reference" "R284"
			(at 0 0 0)
			(layer "B.SilkS")
			(hide yes)
			(effects
				(font
					(size 1.27 1.27)
				)
				(justify mirror)
			)
		)
		(property "Value" "4K7R2F-GP"
			(at -0.064008 -3.993896 0)
			(unlocked yes)
			(layer "B.Fab")
			(hide yes)
			(effects
				(font
					(size 1.016 1.016)
					(thickness 0.1524)
				)
				(justify mirror)
			)
		)
		(property "Device Type" "R402H16"
			(at -0.064008 -5.517896 0)
			(unlocked yes)
			(layer "B.Fab")
			(hide yes)
			(effects
				(font
					(size 1.016 1.016)
					(thickness 0.1524)
				)
				(justify mirror)
			)
		)
		(duplicate_pad_numbers_are_jumpers no)
		(fp_rect
			(start 0.381 0.8382)
			(end -0.381 -0.8382)
			(stroke
				(width 0)
				(type default)
			)
			(fill no)
			(layer "B.CrtYd")
		)
		(fp_rect
			(start 0.381 0.8382)
			(end -0.381 -0.8382)
			(stroke
				(width 0)
				(type default)
			)
			(fill no)
			(layer "B.Fab")
		)
		(pad "1" smd custom
			(at 0 -0.4318 180)
			(size 0.127 0.127)
			(layers "B.Cu" "B.Mask" "B.Paste")
			(net "P1V0")
			(options
				(clearance outline)
				(anchor circle)
			)
			(primitives
				(gr_poly
					(pts
						(arc
							(start -0.2032 0.2794)
							(mid -0.239121 0.264521)
							(end -0.254 0.2286)
						)
						(arc
							(start -0.254 -0.2286)
							(mid -0.239121 -0.264521)
							(end -0.2032 -0.2794)
						)
						(arc
							(start 0.2032 -0.2794)
							(mid 0.239121 -0.264521)
							(end 0.254 -0.2286)
						)
						(arc
							(start 0.254 0.2286)
							(mid 0.239121 0.264521)
							(end 0.2032 0.2794)
						)
					)
					(width 0)
					(fill yes)
				)
			)
		)
		(pad "2" smd custom
			(at 0 0.4318 180)
			(size 0.127 0.127)
			(layers "B.Cu" "B.Mask" "B.Paste")
			(net "SVID_CPU_CLK")
			(options
				(clearance outline)
				(anchor circle)
			)
			(primitives
				(gr_poly
					(pts
						(arc
							(start -0.2032 0.2794)
							(mid -0.239121 0.264521)
							(end -0.254 0.2286)
						)
						(arc
							(start -0.254 -0.2286)
							(mid -0.239121 -0.264521)
							(end -0.2032 -0.2794)
						)
						(arc
							(start 0.2032 -0.2794)
							(mid 0.239121 -0.264521)
							(end 0.254 -0.2286)
						)
						(arc
							(start 0.254 0.2286)
							(mid 0.239121 0.264521)
							(end 0.2032 0.2794)
						)
					)
					(width 0)
					(fill yes)
				)
			)
		)
	)
	(footprint ""
		(layer "B.Cu")
		(at 87.884 -23.241 -90)
		(property "Reference" "C251"
			(at 0 0 90)
			(layer "B.SilkS")
			(hide yes)
			(effects
				(font
					(size 1.27 1.27)
				)
				(justify mirror)
			)
		)
		(property "Value" "SC2D2U10V2KX-GP"
			(at -1.1811 -2.7051 270)
			(unlocked yes)
			(layer "B.Fab")
			(hide yes)
			(effects
				(font
					(size 1.016 1.016)
					(thickness 0.1524)
				)
				(justify mirror)
			)
		)
		(property "Device Type" "C402H22"
			(at -1.1811 -4.2291 270)
			(unlocked yes)
			(layer "B.Fab")
			(hide yes)
			(effects
				(font
					(size 1.016 1.016)
					(thickness 0.1524)
				)
				(justify mirror)
			)
		)
		(duplicate_pad_numbers_are_jumpers no)
		(fp_rect
			(start 0.381 0.7366)
			(end -0.381 -0.7366)
			(stroke
				(width 0)
				(type default)
			)
			(fill no)
			(layer "B.CrtYd")
		)
		(fp_rect
			(start 0.381 0.7366)
			(end -0.381 -0.7366)
			(stroke
				(width 0)
				(type default)
			)
			(fill no)
			(layer "B.Fab")
		)
		(pad "1" smd custom
			(at 0 -0.4572 90)
			(size 0.1143 0.1143)
			(layers "B.Cu" "B.Mask" "B.Paste")
			(net "P1V0")
			(options
				(clearance outline)
				(anchor circle)
			)
			(primitives
				(gr_poly
					(pts
						(arc
							(start -0.254 0.1778)
							(mid -0.239121 0.213721)
							(end -0.2032 0.2286)
						)
						(arc
							(start 0.2032 0.2286)
							(mid 0.239121 0.213721)
							(end 0.254 0.1778)
						)
						(arc
							(start 0.254 -0.1778)
							(mid 0.239121 -0.213721)
							(end 0.2032 -0.2286)
						)
						(arc
							(start -0.2032 -0.2286)
							(mid -0.239121 -0.213721)
							(end -0.254 -0.1778)
						)
					)
					(width 0)
					(fill yes)
				)
			)
		)
		(pad "2" smd custom
			(at 0 0.4572 90)
			(size 0.1143 0.1143)
			(layers "B.Cu" "B.Mask" "B.Paste")
			(net "GND")
			(options
				(clearance outline)
				(anchor circle)
			)
			(primitives
				(gr_poly
					(pts
						(arc
							(start -0.254 0.1778)
							(mid -0.239121 0.213721)
							(end -0.2032 0.2286)
						)
						(arc
							(start 0.2032 0.2286)
							(mid 0.239121 0.213721)
							(end 0.254 0.1778)
						)
						(arc
							(start 0.254 -0.1778)
							(mid 0.239121 -0.213721)
							(end 0.2032 -0.2286)
						)
						(arc
							(start -0.2032 -0.2286)
							(mid -0.239121 -0.213721)
							(end -0.254 -0.1778)
						)
					)
					(width 0)
					(fill yes)
				)
			)
		)
	)
	(footprint ""
		(layer "B.Cu")
		(at 185.2676 -26.3652)
		(property "Reference" "PR148"
			(at 0 0 0)
			(layer "B.SilkS")
			(hide yes)
			(effects
				(font
					(size 1.27 1.27)
				)
				(justify mirror)
			)
		)
		(property "Value" "3K65R2F-1-GP"
			(at -1.7907 -1.1176 0)
			(unlocked yes)
			(layer "B.Fab")
			(hide yes)
			(effects
				(font
					(size 1.016 1.016)
					(thickness 0.1524)
				)
				(justify mirror)
			)
		)
		(property "Device Type" "R402H16"
			(at -1.7907 -2.6416 0)
			(unlocked yes)
			(layer "B.Fab")
			(hide yes)
			(effects
				(font
					(size 1.016 1.016)
					(thickness 0.1524)
				)
				(justify mirror)
			)
		)
		(duplicate_pad_numbers_are_jumpers no)
		(fp_rect
			(start 0.381 0.8382)
			(end -0.381 -0.8382)
			(stroke
				(width 0)
				(type default)
			)
			(fill no)
			(layer "B.CrtYd")
		)
		(fp_rect
			(start 0.381 0.8382)
			(end -0.381 -0.8382)
			(stroke
				(width 0)
				(type default)
			)
			(fill no)
			(layer "B.Fab")
		)
		(pad "1" smd custom
			(at 0 -0.4318 180)
			(size 0.127 0.127)
			(layers "B.Cu" "B.Mask" "B.Paste")
			(net "VR_PVDDRA_ISUMP1")
			(options
				(clearance outline)
				(anchor circle)
			)
			(primitives
				(gr_poly
					(pts
						(arc
							(start -0.2032 0.2794)
							(mid -0.239121 0.264521)
							(end -0.254 0.2286)
						)
						(arc
							(start -0.254 -0.2286)
							(mid -0.239121 -0.264521)
							(end -0.2032 -0.2794)
						)
						(arc
							(start 0.2032 -0.2794)
							(mid 0.239121 -0.264521)
							(end 0.254 -0.2286)
						)
						(arc
							(start 0.254 0.2286)
							(mid 0.239121 0.264521)
							(end 0.2032 0.2794)
						)
					)
					(width 0)
					(fill yes)
				)
			)
		)
		(pad "2" smd custom
			(at 0 0.4318 180)
			(size 0.127 0.127)
			(layers "B.Cu" "B.Mask" "B.Paste")
			(net "VR_PVDDRA_R_IS")
			(options
				(clearance outline)
				(anchor circle)
			)
			(primitives
				(gr_poly
					(pts
						(arc
							(start -0.2032 0.2794)
							(mid -0.239121 0.264521)
							(end -0.254 0.2286)
						)
						(arc
							(start -0.254 -0.2286)
							(mid -0.239121 -0.264521)
							(end -0.2032 -0.2794)
						)
						(arc
							(start 0.2032 -0.2794)
							(mid 0.239121 -0.264521)
							(end 0.254 -0.2286)
						)
						(arc
							(start 0.254 0.2286)
							(mid 0.239121 0.264521)
							(end 0.2032 0.2794)
						)
					)
					(width 0)
					(fill yes)
				)
			)
		)
	)
)
